# S9S_MB_2U (Grand Teton) — schematic netlist excerpt (pin names and nets, part order shuffled) for the footprints in the layout excerpt that follows; sources: Cadence DE-HDL packaged netlist, KiCad conversion of 03242023_DA0F0TMBIJ0_F0T_Motherboard_J_brd_V01_OCP.brd

C720  Q_CAP_DIFFBUS  DIFF BUS_0.22UF 6.3V 20% X6S  pkg C0201  page 176 : \1\ = P5E_CPU1_PE0_TX_C_DN<10> ; \2\ = P5E_CPU1_PE0_TX_DN<10>
C238  Q_CAP  10UF 6.3V 20% X6S  pkg C0402  page 77 : A = PVCCIN_CPU1 ; B = GND
R4063  Q_RES  0 5% CHIP  pkg 0402LF  page 192 : A = E1S_0_EN ; B = P3V3_E1S_EN_1_R

(kicad_pcb
	(version 20260206)
	(generator "pcbnew")
	(generator_version "10.0")
	(general
		(thickness 1.6)
		(legacy_teardrops no)
	)
	(paper "A4")
	(title_block
		(title "03242023_DA0F0TMBIJ0_F0T_Motherboard_J_brd_V01_OCP.brd")
		(comment 1 "Grand Teton / footprints 362-364 of 6105")
	)
	(layers
		(0 "F.Cu" signal "TOP")
		(4 "In1.Cu" signal "GND")
		(6 "In2.Cu" signal "IN1")
		(8 "In3.Cu" signal "GND1")
		(10 "In4.Cu" signal "IN2")
		(12 "In5.Cu" signal "GND2")
		(14 "In6.Cu" signal "IN3")
		(16 "In7.Cu" signal "GND3")
		(18 "In8.Cu" signal "VCC")
		(20 "In9.Cu" signal "VCC1")
		(22 "In10.Cu" signal "GND4")
		(24 "In11.Cu" signal "IN4")
		(26 "In12.Cu" signal "GND5")
		(28 "In13.Cu" signal "IN5")
		(30 "In14.Cu" signal "GND6")
		(32 "In15.Cu" signal "IN6")
		(34 "In16.Cu" signal "GND7")
		(2 "B.Cu" signal "BOTTOM")
		(9 "F.Adhes" user "F.Adhesive")
		(11 "B.Adhes" user "B.Adhesive")
		(13 "F.Paste" user "Package Geometry/Pastemask Top")
		(15 "B.Paste" user "Package Geometry/Pastemask Bottom")
		(5 "F.SilkS" user "Ref Des/Silkscreen Top")
		(7 "B.SilkS" user "Ref Des/Silkscreen Bottom")
		(1 "F.Mask" user "Board Geometry/Soldermask Top")
		(3 "B.Mask" user "Board Geometry/Soldermask Bottom")
		(17 "Dwgs.User" user "User.Drawings")
		(19 "Cmts.User" user "User.Comments")
		(21 "Eco1.User" user "User.Eco1")
		(23 "Eco2.User" user "User.Eco2")
		(25 "Edge.Cuts" user "Board Geometry/Outline")
		(27 "Margin" user)
		(31 "F.CrtYd" user "Package Geometry/Place Bound Top")
		(29 "B.CrtYd" user "Package Geometry/Place Bound Bottom")
		(35 "F.Fab" user "Ref Des/Assembly Top")
		(33 "B.Fab" user "Ref Des/Assembly Bottom")
	)
	(footprint ""
		(layer "F.Cu")
		(at 119.508016 -252.956568 -90)
		(property "Reference" "C238"
			(at 0 0 270)
			(layer "F.SilkS")
			(hide yes)
			(effects
				(font
					(size 1.27 1.27)
				)
			)
		)
		(property "Value" ""
			(at 0 0 270)
			(layer "F.Fab")
			(effects
				(font
					(size 1.27 1.27)
				)
			)
		)
		(duplicate_pad_numbers_are_jumpers no)
		(fp_line
			(start -0.7874 0.4064)
			(end -0.7874 -0.4064)
			(stroke
				(width 0.1524)
				(type default)
			)
			(layer "F.SilkS")
		)
		(fp_line
			(start 0.7874 0.4064)
			(end -0.7874 0.4064)
			(stroke
				(width 0.1524)
				(type default)
			)
			(layer "F.SilkS")
		)
		(fp_line
			(start -0.7874 -0.4064)
			(end 0.7874 -0.4064)
			(stroke
				(width 0.1524)
				(type default)
			)
			(layer "F.SilkS")
		)
		(fp_line
			(start 0.7874 -0.4064)
			(end 0.7874 0.4064)
			(stroke
				(width 0.1524)
				(type default)
			)
			(layer "F.SilkS")
		)
		(fp_line
			(start -0.67945 0.3048)
			(end -0.67945 -0.305054)
			(stroke
				(width 0.1)
				(type default)
			)
			(layer "F.Fab")
		)
		(fp_line
			(start -0.12065 0.3048)
			(end -0.67945 0.3048)
			(stroke
				(width 0.1)
				(type default)
			)
			(layer "F.Fab")
		)
		(fp_line
			(start 0.120396 0.3048)
			(end 0.120396 0.2794)
			(stroke
				(width 0.1)
				(type default)
			)
			(layer "F.Fab")
		)
		(fp_line
			(start 0.67945 0.3048)
			(end 0.120396 0.3048)
			(stroke
				(width 0.1)
				(type default)
			)
			(layer "F.Fab")
		)
		(fp_line
			(start -0.12065 0.2794)
			(end -0.12065 0.3048)
			(stroke
				(width 0.1)
				(type default)
			)
			(layer "F.Fab")
		)
		(fp_line
			(start 0.120396 0.2794)
			(end -0.12065 0.2794)
			(stroke
				(width 0.1)
				(type default)
			)
			(layer "F.Fab")
		)
		(fp_line
			(start -0.12065 -0.2794)
			(end 0.12065 -0.2794)
			(stroke
				(width 0.1)
				(type default)
			)
			(layer "F.Fab")
		)
		(fp_line
			(start 0.12065 -0.2794)
			(end 0.12065 -0.3048)
			(stroke
				(width 0.1)
				(type default)
			)
			(layer "F.Fab")
		)
		(fp_line
			(start 0.12065 -0.3048)
			(end 0.67945 -0.3048)
			(stroke
				(width 0.1)
				(type default)
			)
			(layer "F.Fab")
		)
		(fp_line
			(start 0.67945 -0.3048)
			(end 0.67945 0.3048)
			(stroke
				(width 0.1)
				(type default)
			)
			(layer "F.Fab")
		)
		(fp_line
			(start -0.67945 -0.305054)
			(end -0.12065 -0.305054)
			(stroke
				(width 0.1)
				(type default)
			)
			(layer "F.Fab")
		)
		(fp_line
			(start -0.12065 -0.305054)
			(end -0.12065 -0.2794)
			(stroke
				(width 0.1)
				(type default)
			)
			(layer "F.Fab")
		)
		(pad "1" smd circle
			(at -0.40005 0 270)
			(size 0 0)
			(layers "F.Cu" "F.Mask" "F.Paste")
			(net "PVCCIN_CPU1")
		)
		(pad "2" smd circle
			(at 0.40005 0 270)
			(size 0 0)
			(layers "F.Cu" "F.Mask" "F.Paste")
			(net "GND")
		)
	)
	(footprint ""
		(layer "F.Cu")
		(at 63.270638 -402.371052 -90)
		(property "Reference" "C720"
			(at 0 0 270)
			(layer "F.SilkS")
			(hide yes)
			(effects
				(font
					(size 1.27 1.27)
				)
			)
		)
		(property "Value" ""
			(at 0 0 270)
			(layer "F.Fab")
			(effects
				(font
					(size 1.27 1.27)
				)
			)
		)
		(duplicate_pad_numbers_are_jumpers no)
		(fp_line
			(start -0.299974 0.150114)
			(end -0.299974 -0.150114)
			(stroke
				(width 0.1)
				(type default)
			)
			(layer "F.Fab")
		)
		(fp_line
			(start 0.299974 0.150114)
			(end -0.299974 0.150114)
			(stroke
				(width 0.1)
				(type default)
			)
			(layer "F.Fab")
		)
		(fp_line
			(start -0.299974 -0.150114)
			(end 0.299974 -0.150114)
			(stroke
				(width 0.1)
				(type default)
			)
			(layer "F.Fab")
		)
		(fp_line
			(start 0.299974 -0.150114)
			(end 0.299974 0.150114)
			(stroke
				(width 0.1)
				(type default)
			)
			(layer "F.Fab")
		)
		(pad "1" smd rect
			(at -0.2667 0 270)
			(size 0.3048 0.381)
			(layers "F.Cu" "F.Mask" "F.Paste")
			(net "P5E_CPU1_PE0_TX_C_DN<10>")
		)
		(pad "2" smd rect
			(at 0.2667 0 270)
			(size 0.3048 0.381)
			(layers "F.Cu" "F.Mask" "F.Paste")
			(net "P5E_CPU1_PE0_TX_DN<10>")
		)
	)
	(footprint ""
		(layer "F.Cu")
		(at 292.79088 -46.954948 90)
		(property "Reference" "R4063"
			(at 0 0 90)
			(layer "F.SilkS")
			(hide yes)
			(effects
				(font
					(size 1.27 1.27)
				)
			)
		)
		(property "Value" ""
			(at 0 0 90)
			(layer "F.Fab")
			(effects
				(font
					(size 1.27 1.27)
				)
			)
		)
		(duplicate_pad_numbers_are_jumpers no)
		(fp_line
			(start 0.7874 -0.4064)
			(end 0.7874 0.4064)
			(stroke
				(width 0.1524)
				(type default)
			)
			(layer "F.SilkS")
		)
		(fp_line
			(start -0.7874 -0.4064)
			(end 0.7874 -0.4064)
			(stroke
				(width 0.1524)
				(type default)
			)
			(layer "F.SilkS")
		)
		(fp_line
			(start 0.7874 0.4064)
			(end -0.7874 0.4064)
			(stroke
				(width 0.1524)
				(type default)
			)
			(layer "F.SilkS")
		)
		(fp_line
			(start -0.7874 0.4064)
			(end -0.7874 -0.4064)
			(stroke
				(width 0.1524)
				(type default)
			)
			(layer "F.SilkS")
		)
		(fp_line
			(start -0.12065 -0.305054)
			(end -0.12065 -0.2794)
			(stroke
				(width 0.1)
				(type default)
			)
			(layer "F.Fab")
		)
		(fp_line
			(start -0.67945 -0.305054)
			(end -0.12065 -0.305054)
			(stroke
				(width 0.1)
				(type default)
			)
			(layer "F.Fab")
		)
		(fp_line
			(start 0.67945 -0.3048)
			(end 0.67945 0.3048)
			(stroke
				(width 0.1)
				(type default)
			)
			(layer "F.Fab")
		)
		(fp_line
			(start 0.12065 -0.3048)
			(end 0.67945 -0.3048)
			(stroke
				(width 0.1)
				(type default)
			)
			(layer "F.Fab")
		)
		(fp_line
			(start 0.12065 -0.2794)
			(end 0.12065 -0.3048)
			(stroke
				(width 0.1)
				(type default)
			)
			(layer "F.Fab")
		)
		(fp_line
			(start -0.12065 -0.2794)
			(end 0.12065 -0.2794)
			(stroke
				(width 0.1)
				(type default)
			)
			(layer "F.Fab")
		)
		(fp_line
			(start 0.120396 0.2794)
			(end -0.12065 0.2794)
			(stroke
				(width 0.1)
				(type default)
			)
			(layer "F.Fab")
		)
		(fp_line
			(start -0.12065 0.2794)
			(end -0.12065 0.3048)
			(stroke
				(width 0.1)
				(type default)
			)
			(layer "F.Fab")
		)
		(fp_line
			(start 0.67945 0.3048)
			(end 0.120396 0.3048)
			(stroke
				(width 0.1)
				(type default)
			)
			(layer "F.Fab")
		)
		(fp_line
			(start 0.120396 0.3048)
			(end 0.120396 0.2794)
			(stroke
				(width 0.1)
				(type default)
			)
			(layer "F.Fab")
		)
		(fp_line
			(start -0.12065 0.3048)
			(end -0.67945 0.3048)
			(stroke
				(width 0.1)
				(type default)
			)
			(layer "F.Fab")
		)
		(fp_line
			(start -0.67945 0.3048)
			(end -0.67945 -0.305054)
			(stroke
				(width 0.1)
				(type default)
			)
			(layer "F.Fab")
		)
		(pad "1" smd circle
			(at -0.40005 0 90)
			(size 0 0)
			(layers "F.Cu" "F.Mask" "F.Paste")
			(net "E1S_0_EN")
		)
		(pad "2" smd circle
			(at 0.40005 0 90)
			(size 0 0)
			(layers "F.Cu" "F.Mask" "F.Paste")
			(net "P3V3_E1S_EN_1_R")
		)
	)
)
